(kicad_pcb
	(version 20260206)
	(generator "pcbnew")
	(generator_version "10.0")
	(general
		(thickness 1.6)
		(legacy_teardrops no)
	)
	(paper "A4")
	(title_block
		(title "01162023_DA0F0TEBIF0_F0T_Expander_BD_F_brd_V02_OCP.brd")
		(comment 1 "Grand Teton / footprints 4833-4839 of 9728")
	)
	(layers
		(0 "F.Cu" signal "TOP")
		(4 "In1.Cu" signal "GND")
		(6 "In2.Cu" signal "VCC")
		(8 "In3.Cu" signal "VCC1")
		(10 "In4.Cu" signal "GND1")
		(12 "In5.Cu" signal "IN1")
		(14 "In6.Cu" signal "GND2")
		(16 "In7.Cu" signal "IN2")
		(18 "In8.Cu" signal "GND3")
		(20 "In9.Cu" signal "IN3")
		(22 "In10.Cu" signal "GND4")
		(24 "In11.Cu" signal "IN4")
		(26 "In12.Cu" signal "GND5")
		(28 "In13.Cu" signal "IN5")
		(30 "In14.Cu" signal "GND6")
		(32 "In15.Cu" signal "IN6")
		(34 "In16.Cu" signal "GND7")
		(2 "B.Cu" signal "BOTTOM")
		(9 "F.Adhes" user "F.Adhesive")
		(11 "B.Adhes" user "B.Adhesive")
		(13 "F.Paste" user "Package Geometry/Pastemask Top")
		(15 "B.Paste" user "Package Geometry/Pastemask Bottom")
		(5 "F.SilkS" user "Ref Des/Silkscreen Top")
		(7 "B.SilkS" user "Ref Des/Silkscreen Bottom")
		(1 "F.Mask" user "Board Geometry/Soldermask Top")
		(3 "B.Mask" user "Board Geometry/Soldermask Bottom")
		(17 "Dwgs.User" user "User.Drawings")
		(19 "Cmts.User" user "User.Comments")
		(21 "Eco1.User" user "User.Eco1")
		(23 "Eco2.User" user "User.Eco2")
		(25 "Edge.Cuts" user "Board Geometry/Outline")
		(27 "Margin" user)
		(31 "F.CrtYd" user "Package Geometry/Place Bound Top")
		(29 "B.CrtYd" user "Package Geometry/Place Bound Bottom")
		(35 "F.Fab" user "Ref Des/Assembly Top")
		(33 "B.Fab" user "Ref Des/Assembly Bottom")
	)
	(footprint ""
		(layer "F.Cu")
		(at 8.45058 -73.475088)
		(property "Reference" "R5652"
			(at 0 0 0)
			(layer "F.SilkS")
			(hide yes)
			(effects
				(font
					(size 1.27 1.27)
				)
			)
		)
		(property "Value" ""
			(at 0 0 0)
			(layer "F.Fab")
			(effects
				(font
					(size 1.27 1.27)
				)
			)
		)
		(duplicate_pad_numbers_are_jumpers no)
		(fp_line
			(start -0.7874 -0.4064)
			(end 0.7874 -0.4064)
			(stroke
				(width 0.1524)
				(type default)
			)
			(layer "F.SilkS")
		)
		(fp_line
			(start -0.7874 0.4064)
			(end -0.7874 -0.4064)
			(stroke
				(width 0.1524)
				(type default)
			)
			(layer "F.SilkS")
		)
		(fp_line
			(start 0.7874 -0.4064)
			(end 0.7874 0.4064)
			(stroke
				(width 0.1524)
				(type default)
			)
			(layer "F.SilkS")
		)
		(fp_line
			(start 0.7874 0.4064)
			(end -0.7874 0.4064)
			(stroke
				(width 0.1524)
				(type default)
			)
			(layer "F.SilkS")
		)
		(fp_line
			(start -0.67945 -0.305054)
			(end -0.12065 -0.305054)
			(stroke
				(width 0.1)
				(type default)
			)
			(layer "F.Fab")
		)
		(fp_line
			(start -0.67945 0.3048)
			(end -0.67945 -0.305054)
			(stroke
				(width 0.1)
				(type default)
			)
			(layer "F.Fab")
		)
		(fp_line
			(start -0.12065 -0.305054)
			(end -0.12065 -0.2794)
			(stroke
				(width 0.1)
				(type default)
			)
			(layer "F.Fab")
		)
		(fp_line
			(start -0.12065 -0.2794)
			(end 0.12065 -0.2794)
			(stroke
				(width 0.1)
				(type default)
			)
			(layer "F.Fab")
		)
		(fp_line
			(start -0.12065 0.2794)
			(end -0.12065 0.3048)
			(stroke
				(width 0.1)
				(type default)
			)
			(layer "F.Fab")
		)
		(fp_line
			(start -0.12065 0.3048)
			(end -0.67945 0.3048)
			(stroke
				(width 0.1)
				(type default)
			)
			(layer "F.Fab")
		)
		(fp_line
			(start 0.120396 0.2794)
			(end -0.12065 0.2794)
			(stroke
				(width 0.1)
				(type default)
			)
			(layer "F.Fab")
		)
		(fp_line
			(start 0.120396 0.3048)
			(end 0.120396 0.2794)
			(stroke
				(width 0.1)
				(type default)
			)
			(layer "F.Fab")
		)
		(fp_line
			(start 0.12065 -0.3048)
			(end 0.67945 -0.3048)
			(stroke
				(width 0.1)
				(type default)
			)
			(layer "F.Fab")
		)
		(fp_line
			(start 0.12065 -0.2794)
			(end 0.12065 -0.3048)
			(stroke
				(width 0.1)
				(type default)
			)
			(layer "F.Fab")
		)
		(fp_line
			(start 0.67945 -0.3048)
			(end 0.67945 0.3048)
			(stroke
				(width 0.1)
				(type default)
			)
			(layer "F.Fab")
		)
		(fp_line
			(start 0.67945 0.3048)
			(end 0.120396 0.3048)
			(stroke
				(width 0.1)
				(type default)
			)
			(layer "F.Fab")
		)
		(pad "1" smd circle
			(at -0.40005 0)
			(size 0 0)
			(layers "F.Cu" "F.Mask" "F.Paste")
			(net "RST_SMB_SSD0_ISO_N")
		)
		(pad "2" smd circle
			(at 0.40005 0)
			(size 0 0)
			(layers "F.Cu" "F.Mask" "F.Paste")
			(net "P3V3_SSD0")
		)
	)
	(footprint ""
		(layer "F.Cu")
		(at 133.892544 -29.139642 180)
		(property "Reference" "C282"
			(at 0 0 180)
			(layer "F.SilkS")
			(hide yes)
			(effects
				(font
					(size 1.27 1.27)
				)
			)
		)
		(property "Value" ""
			(at 0 0 180)
			(layer "F.Fab")
			(effects
				(font
					(size 1.27 1.27)
				)
			)
		)
		(duplicate_pad_numbers_are_jumpers no)
		(fp_line
			(start 0.299974 0.150114)
			(end -0.299974 0.150114)
			(stroke
				(width 0.1)
				(type default)
			)
			(layer "F.Fab")
		)
		(fp_line
			(start 0.299974 -0.150114)
			(end 0.299974 0.150114)
			(stroke
				(width 0.1)
				(type default)
			)
			(layer "F.Fab")
		)
		(fp_line
			(start -0.299974 0.150114)
			(end -0.299974 -0.150114)
			(stroke
				(width 0.1)
				(type default)
			)
			(layer "F.Fab")
		)
		(fp_line
			(start -0.299974 -0.150114)
			(end 0.299974 -0.150114)
			(stroke
				(width 0.1)
				(type default)
			)
			(layer "F.Fab")
		)
		(pad "1" smd rect
			(at -0.2667 0 180)
			(size 0.3048 0.381)
			(layers "F.Cu" "F.Mask" "F.Paste")
			(net "P5E_PEX1_STN2_TX_DP<44>")
		)
		(pad "2" smd rect
			(at 0.2667 0 180)
			(size 0.3048 0.381)
			(layers "F.Cu" "F.Mask" "F.Paste")
			(net "P5E_PEX1_STN2_TX_C_DP<44>")
		)
	)
	(footprint ""
		(layer "F.Cu")
		(at 26.439368 -356.244906 90)
		(property "Reference" "C2159"
			(at 0 0 90)
			(layer "F.SilkS")
			(hide yes)
			(effects
				(font
					(size 1.27 1.27)
				)
			)
		)
		(property "Value" ""
			(at 0 0 90)
			(layer "F.Fab")
			(effects
				(font
					(size 1.27 1.27)
				)
			)
		)
		(duplicate_pad_numbers_are_jumpers no)
		(fp_line
			(start 0.299974 -0.150114)
			(end 0.299974 0.150114)
			(stroke
				(width 0.1)
				(type default)
			)
			(layer "F.Fab")
		)
		(fp_line
			(start -0.299974 -0.150114)
			(end 0.299974 -0.150114)
			(stroke
				(width 0.1)
				(type default)
			)
			(layer "F.Fab")
		)
		(fp_line
			(start 0.299974 0.150114)
			(end -0.299974 0.150114)
			(stroke
				(width 0.1)
				(type default)
			)
			(layer "F.Fab")
		)
		(fp_line
			(start -0.299974 0.150114)
			(end -0.299974 -0.150114)
			(stroke
				(width 0.1)
				(type default)
			)
			(layer "F.Fab")
		)
		(pad "1" smd rect
			(at -0.2667 0 90)
			(size 0.3048 0.381)
			(layers "F.Cu" "F.Mask" "F.Paste")
			(net "P5E_PEX0_STN4_TX_DN<76>")
		)
		(pad "2" smd rect
			(at 0.2667 0 90)
			(size 0.3048 0.381)
			(layers "F.Cu" "F.Mask" "F.Paste")
			(net "P5E_PEX0_STN4_TX_C_DN<76>")
		)
	)
	(footprint ""
		(layer "F.Cu")
		(at 455.93254 -5.999988)
		(property "Reference" "H48"
			(at -5.198618 -5.53593 0)
			(unlocked yes)
			(layer "F.SilkS")
			(effects
				(font
					(size 0.7874 0.5842)
					(thickness 0.1524)
				)
				(justify left)
			)
		)
		(property "Value" ""
			(at 0 0 0)
			(layer "F.Fab")
			(effects
				(font
					(size 1.27 1.27)
				)
			)
		)
		(duplicate_pad_numbers_are_jumpers no)
		(pad "1" thru_hole circle
			(at 0 0)
			(size 10.0076 10.0076)
			(drill 5.6134)
			(layers "*.Cu" "*.Mask")
			(remove_unused_layers no)
			(net "GND")
			(clearance -1.9431)
		)
	)
	(footprint ""
		(layer "F.Cu")
		(at 30.153356 -300.992032)
		(property "Reference" "L89"
			(at 0 0 0)
			(layer "F.SilkS")
			(hide yes)
			(effects
				(font
					(size 1.27 1.27)
				)
			)
		)
		(property "Value" ""
			(at 0 0 0)
			(layer "F.Fab")
			(effects
				(font
					(size 1.27 1.27)
				)
			)
		)
		(duplicate_pad_numbers_are_jumpers no)
		(fp_line
			(start -1.63576 -0.8128)
			(end -1.63576 0.8128)
			(stroke
				(width 0.1524)
				(type default)
			)
			(layer "F.SilkS")
		)
		(fp_line
			(start -1.63576 -0.8128)
			(end 1.63576 -0.8128)
			(stroke
				(width 0.1524)
				(type default)
			)
			(layer "F.SilkS")
		)
		(fp_line
			(start 1.63576 -0.8128)
			(end 1.63576 0.8128)
			(stroke
				(width 0.1524)
				(type default)
			)
			(layer "F.SilkS")
		)
		(fp_line
			(start 1.63576 0.8128)
			(end -1.63576 0.8128)
			(stroke
				(width 0.1524)
				(type default)
			)
			(layer "F.SilkS")
		)
		(fp_line
			(start -1.56083 -0.738632)
			(end -1.56083 0.7366)
			(stroke
				(width 0.1)
				(type default)
			)
			(layer "F.Fab")
		)
		(fp_line
			(start -1.56083 0.7366)
			(end -1.524 0.7366)
			(stroke
				(width 0.1)
				(type default)
			)
			(layer "F.Fab")
		)
		(fp_line
			(start -1.524 0.7366)
			(end 1.524 0.7366)
			(stroke
				(width 0.1)
				(type default)
			)
			(layer "F.Fab")
		)
		(fp_line
			(start 1.524 0.7366)
			(end 1.560576 0.7366)
			(stroke
				(width 0.1)
				(type default)
			)
			(layer "F.Fab")
		)
		(fp_line
			(start 1.560576 -0.738632)
			(end -1.56083 -0.738632)
			(stroke
				(width 0.1)
				(type default)
			)
			(layer "F.Fab")
		)
		(fp_line
			(start 1.560576 0.7366)
			(end 1.560576 -0.738632)
			(stroke
				(width 0.1)
				(type default)
			)
			(layer "F.Fab")
		)
		(pad "1" smd rect
			(at -0.94996 0 180)
			(size 1.1176 1.3716)
			(layers "F.Cu" "F.Mask" "F.Paste")
			(net "P1V8_PLL0_PEX0")
		)
		(pad "2" smd rect
			(at 0.94996 0 180)
			(size 1.1176 1.3716)
			(layers "F.Cu" "F.Mask" "F.Paste")
			(net "PCEPLL1_VDDA18_PEX0")
		)
	)
	(footprint ""
		(layer "F.Cu")
		(at 2.633218 -393.46632 -90)
		(property "Reference" "R6744"
			(at 0 0 270)
			(layer "F.SilkS")
			(hide yes)
			(effects
				(font
					(size 1.27 1.27)
				)
			)
		)
		(property "Value" ""
			(at 0 0 270)
			(layer "F.Fab")
			(effects
				(font
					(size 1.27 1.27)
				)
			)
		)
		(duplicate_pad_numbers_are_jumpers no)
		(fp_line
			(start -0.7874 0.4064)
			(end -0.7874 -0.4064)
			(stroke
				(width 0.1524)
				(type default)
			)
			(layer "F.SilkS")
		)
		(fp_line
			(start 0.7874 0.4064)
			(end -0.7874 0.4064)
			(stroke
				(width 0.1524)
				(type default)
			)
			(layer "F.SilkS")
		)
		(fp_line
			(start -0.7874 -0.4064)
			(end 0.7874 -0.4064)
			(stroke
				(width 0.1524)
				(type default)
			)
			(layer "F.SilkS")
		)
		(fp_line
			(start 0.7874 -0.4064)
			(end 0.7874 0.4064)
			(stroke
				(width 0.1524)
				(type default)
			)
			(layer "F.SilkS")
		)
		(fp_line
			(start -0.67945 0.3048)
			(end -0.67945 -0.305054)
			(stroke
				(width 0.1)
				(type default)
			)
			(layer "F.Fab")
		)
		(fp_line
			(start -0.12065 0.3048)
			(end -0.67945 0.3048)
			(stroke
				(width 0.1)
				(type default)
			)
			(layer "F.Fab")
		)
		(fp_line
			(start 0.120396 0.3048)
			(end 0.120396 0.2794)
			(stroke
				(width 0.1)
				(type default)
			)
			(layer "F.Fab")
		)
		(fp_line
			(start 0.67945 0.3048)
			(end 0.120396 0.3048)
			(stroke
				(width 0.1)
				(type default)
			)
			(layer "F.Fab")
		)
		(fp_line
			(start -0.12065 0.2794)
			(end -0.12065 0.3048)
			(stroke
				(width 0.1)
				(type default)
			)
			(layer "F.Fab")
		)
		(fp_line
			(start 0.120396 0.2794)
			(end -0.12065 0.2794)
			(stroke
				(width 0.1)
				(type default)
			)
			(layer "F.Fab")
		)
		(fp_line
			(start -0.12065 -0.2794)
			(end 0.12065 -0.2794)
			(stroke
				(width 0.1)
				(type default)
			)
			(layer "F.Fab")
		)
		(fp_line
			(start 0.12065 -0.2794)
			(end 0.12065 -0.3048)
			(stroke
				(width 0.1)
				(type default)
			)
			(layer "F.Fab")
		)
		(fp_line
			(start 0.12065 -0.3048)
			(end 0.67945 -0.3048)
			(stroke
				(width 0.1)
				(type default)
			)
			(layer "F.Fab")
		)
		(fp_line
			(start 0.67945 -0.3048)
			(end 0.67945 0.3048)
			(stroke
				(width 0.1)
				(type default)
			)
			(layer "F.Fab")
		)
		(fp_line
			(start -0.67945 -0.305054)
			(end -0.12065 -0.305054)
			(stroke
				(width 0.1)
				(type default)
			)
			(layer "F.Fab")
		)
		(fp_line
			(start -0.12065 -0.305054)
			(end -0.12065 -0.2794)
			(stroke
				(width 0.1)
				(type default)
			)
			(layer "F.Fab")
		)
		(pad "1" smd circle
			(at -0.40005 0 270)
			(size 0 0)
			(layers "F.Cu" "F.Mask" "F.Paste")
			(net "P3V3_USB_8042")
		)
		(pad "2" smd circle
			(at 0.40005 0 270)
			(size 0 0)
			(layers "F.Cu" "F.Mask" "F.Paste")
			(net "BIC_USB_8042_HUB_GRSTZ")
		)
	)
	(footprint ""
		(layer "F.Cu")
		(at 199.689466 -63.56223)
		(property "Reference" "Q203"
			(at 0.42291 -2.23901 0)
			(unlocked yes)
			(layer "F.SilkS")
			(effects
				(font
					(size 0.7874 0.5842)
					(thickness 0.1524)
				)
			)
		)
		(property "Value" ""
			(at 0 0 0)
			(layer "F.Fab")
			(effects
				(font
					(size 1.27 1.27)
				)
			)
		)
		(duplicate_pad_numbers_are_jumpers no)
		(fp_line
			(start -1.376172 -1.199896)
			(end -0.508 -1.199896)
			(stroke
				(width 0.1524)
				(type default)
			)
			(layer "F.SilkS")
		)
		(fp_line
			(start -1.376172 1.199896)
			(end -1.376172 -1.199896)
			(stroke
				(width 0.1524)
				(type default)
			)
			(layer "F.SilkS")
		)
		(fp_line
			(start -0.508 -1.199896)
			(end 0 -0.762)
			(stroke
				(width 0.1524)
				(type default)
			)
			(layer "F.SilkS")
		)
		(fp_line
			(start 0 -0.762)
			(end 0.508 -1.199896)
			(stroke
				(width 0.1524)
				(type default)
			)
			(layer "F.SilkS")
		)
		(fp_line
			(start 0.508 -1.199896)
			(end 1.376172 -1.199896)
			(stroke
				(width 0.1524)
				(type default)
			)
			(layer "F.SilkS")
		)
		(fp_line
			(start 1.376172 -1.199896)
			(end 1.376172 1.199896)
			(stroke
				(width 0.1524)
				(type default)
			)
			(layer "F.SilkS")
		)
		(fp_line
			(start 1.376172 1.199896)
			(end -1.376172 1.199896)
			(stroke
				(width 0.1524)
				(type default)
			)
			(layer "F.SilkS")
		)
		(fp_poly
			(pts
				(xy -1.382014 -1.13665) (xy -1.651254 -1.944878) (xy -2.190242 -1.40589)
			)
			(stroke
				(width 0)
				(type default)
			)
			(fill yes)
			(layer "F.SilkS")
		)
		(fp_line
			(start -0.674878 -1.100074)
			(end 0.674878 -1.100074)
			(stroke
				(width 0.1)
				(type default)
			)
			(layer "F.Fab")
		)
		(fp_line
			(start -0.674878 1.100074)
			(end -0.674878 -1.100074)
			(stroke
				(width 0.1)
				(type default)
			)
			(layer "F.Fab")
		)
		(fp_line
			(start 0.674878 -1.100074)
			(end 0.674878 1.100074)
			(stroke
				(width 0.1)
				(type default)
			)
			(layer "F.Fab")
		)
		(fp_line
			(start 0.674878 1.100074)
			(end -0.674878 1.100074)
			(stroke
				(width 0.1)
				(type default)
			)
			(layer "F.Fab")
		)
		(fp_poly
			(pts
				(xy -1.4605 -0.7493) (xy -2.2225 -1.1303) (xy -2.2225 -0.3683)
			)
			(stroke
				(width 0)
				(type default)
			)
			(fill yes)
			(layer "F.Fab")
		)
		(pad "1" smd rect
			(at -0.899922 -0.750062 270)
			(size 0.6096 0.6096)
			(layers "F.Cu" "F.Mask" "F.Paste")
			(net "GND")
		)
		(pad "2" smd rect
			(at -0.899922 0 270)
			(size 0.4064 0.6096)
			(layers "F.Cu" "F.Mask" "F.Paste")
			(net "P12V_SSD7_PG_G1")
		)
		(pad "3" smd rect
			(at -0.899922 0.750062 270)
			(size 0.6096 0.6096)
			(layers "F.Cu" "F.Mask" "F.Paste")
			(net "PWRGD_P12V_SSD7_D")
		)
		(pad "4" smd rect
			(at 0.899922 0.750062 270)
			(size 0.6096 0.6096)
			(layers "F.Cu" "F.Mask" "F.Paste")
			(net "GND")
		)
		(pad "5" smd rect
			(at 0.899922 0 270)
			(size 0.4064 0.6096)
			(layers "F.Cu" "F.Mask" "F.Paste")
			(net "P12V_SSD7_PG_G2")
		)
		(pad "6" smd rect
			(at 0.899922 -0.750062 270)
			(size 0.6096 0.6096)
			(layers "F.Cu" "F.Mask" "F.Paste")
			(net "P12V_SSD7_PG_G2")
		)
	)
)
